G04 ================== begin FILE IDENTIFICATION RECORD ==================*
G04 Layout Name:  12004-1.brd*
G04 Film Name:    GOLD_B*
G04 File Format:  Gerber RS274X*
G04 File Origin:  Cadence Allegro 16.2-S033*
G04 Origin Date:  Tue Oct 16 17:03:28 2012*
G04 *
G04 Layer:  DRAWING FORMAT/LAYER_GOLD_B*
G04 Layer:  DRAWING FORMAT/LAYER_PCB_STORY*
G04 Layer:  BOARD GEOMETRY/GOLDEN_BOTTOM*
G04 Layer:  BOARD GEOMETRY/PANEL_OUTLINE*
G04 *
G04 Offset:    (0.00 0.00)*
G04 Mirror:    No*
G04 Mode:      Positive*
G04 Rotation:  0*
G04 FullContactRelief:  No*
G04 UndefLineWidth:     6.00*
G04 ================== end FILE IDENTIFICATION RECORD ====================*
%FSLAX35Y35*MOIN*%
%IR0*IPPOS*OFA0.00000B0.00000*MIA0B0*SFA1.00000B1.00000*%
%ADD10C,.02*%
%ADD11C,.006*%
G75*
%LPD*%
G75*
G36*
G01X773215Y660133D02*
Y328133D01*
X795315D01*
Y660133D01*
X773215D01*
G37*
G36*
G01Y817533D02*
Y737633D01*
X795315D01*
Y817533D01*
X773215D01*
G37*
G54D10*
G01X-771361Y-182763D02*
Y-262763D01*
G01Y-218263D02*
X373639D01*
G01X-771361Y-262763D02*
X373639D01*
G01X-775361Y-166763D02*
G02I-12000J0D01*
G01X-780511D02*
G02I-6850J0D01*
G01X-787361Y-182763D02*
Y-150763D01*
G01X-771361Y-166763D02*
X-803361D01*
G01X-771361Y-182763D02*
X373639D01*
G01X-413861D02*
Y-262763D01*
G01X-276361Y-182763D02*
Y-262763D01*
G01X-161361Y-182763D02*
Y-262763D01*
G01X6139Y-182763D02*
Y-262763D01*
G01X176139Y-182763D02*
Y-262763D01*
G01X373639Y-182763D02*
Y-262763D01*
G01X401639Y-166763D02*
G02I-12000J0D01*
G01X396489D02*
G02I-6850J0D01*
G01X389639Y-182763D02*
Y-150763D01*
G01X405639Y-166763D02*
X373639D01*
G54D11*
G01X-1003937Y-3937D02*
G03X-1000000Y-7874I3937J0D01*
G01X-1031496Y-31496D02*
G03X-1027559Y-35433I3937J0D01*
G01X-986221Y-7874D02*
G03Y0I0J3937D01*
G01Y-7874D02*
X-1000000D01*
G01X-1027559Y-35433D02*
X791338D01*
G01X-1031496Y95866D02*
Y-31496D01*
G01X-996063Y3937D02*
G03X-992126Y0I3937J0D01*
G01X-996063Y39370D02*
G03X-1003937I-3937J0D01*
G01X-996063Y3937D02*
G03X-992126Y0I3937J0D01*
G01D02*
X-318898D01*
G01D02*
X-992126D01*
G01X-955512D02*
X-986221D01*
G01X-996063Y3937D02*
Y103740D01*
G01Y39370D02*
Y70079D01*
G01X-1003937Y-3937D02*
Y39370D01*
G01X-1027559Y99803D02*
G03X-1031496Y95866I0J-3937D01*
G01X-1003937D02*
G03X-1007874Y99803I-3937J0D01*
G01X-996063Y103740D02*
G03X-1000000Y107677I-3937J0D01*
G01X-1003937Y70079D02*
G03X-996063I3937J0D01*
G01X-1029528Y107677D02*
X-1000000D01*
G01X-1007874Y99803D02*
X-1027559D01*
G01X-1003937Y70079D02*
Y95866D01*
G01X-1031496Y109646D02*
X-1029528Y107677D01*
G01X-1031496Y109646D02*
Y134055D01*
G01X-1002166Y136024D02*
G03Y143504I0J3740D01*
G01X-1000000Y187599D02*
G03X-996063Y191536I0J3937D01*
G01X-1029528Y187599D02*
X-1000000D01*
G01X-1029528Y143504D02*
X-1002166D01*
G01X-1029528Y136024D02*
X-1002166D01*
G01X-1029528D02*
X-1031496Y134055D01*
G01X-1029528Y187599D02*
X-1031496Y185630D01*
G01Y145473D02*
X-1029528Y143504D01*
G01X-996063Y261221D02*
Y191536D01*
G01X-1031496Y145473D02*
Y185630D01*
G01X-996063Y261221D02*
G03X-1000000Y265158I-3937J0D01*
G01X-1029528D02*
X-1000000D01*
G01X-1031496Y267126D02*
X-1029528Y265158D01*
G01X-1031496Y267126D02*
Y543504D01*
G01X-1002166Y545473D02*
G03Y552953I0J3740D01*
G01X-1029528D02*
X-1002166D01*
G01X-1029528Y545473D02*
X-1002166D01*
G01X-1031496Y554922D02*
X-1029528Y552953D01*
G01Y545473D02*
X-1031496Y543504D01*
G01Y554922D02*
Y595079D01*
G01X-1007874Y604922D02*
G03X-1003937Y608859I0J3937D01*
G01X-1031496D02*
G03X-1027559Y604922I3937J0D01*
G01X-1000000Y597048D02*
G03X-996063Y600985I0J3937D01*
G01X-1027559Y604922D02*
X-1007874D01*
G01X-1029528Y597048D02*
X-1000000D01*
G01X-1029528D02*
X-1031496Y595079D01*
G01X-996063Y921260D02*
Y600985D01*
G01X-1003937Y608859D02*
Y708662D01*
G01X-1031496Y956693D02*
Y608859D01*
G01X-1003937Y739370D02*
G03X-996063I3937J0D01*
G01Y708662D02*
G03X-1003937I-3937J0D01*
G01X-996063D02*
Y739370D01*
G01X-1003937D02*
Y929134D01*
G01X-992126Y925197D02*
G03X-996063Y921260I0J-3937D01*
G01X-1000000Y933071D02*
G03X-1003937Y929134I0J-3937D01*
G01X-986221Y925197D02*
G03Y933071I0J3937D01*
G01X-1027559Y960630D02*
G03X-1031496Y956693I0J-3937D01*
G01X-992126Y925197D02*
G03X-996063Y921260I0J-3937D01*
G01X791338Y960630D02*
X-1027559D01*
G01X-1000000Y933071D02*
X-986221D01*
G01X-992126Y925197D02*
X-240158D01*
G01X-986221D02*
X-955512D01*
G01X-992126D02*
X-240158D01*
G01X-955512Y0D02*
G03Y-7874I0J-3937D01*
G01X-769685D02*
X-955512D01*
G01Y933071D02*
G03Y925197I0J-3937D01*
G01Y933071D02*
X-750000D01*
G01X-769685Y-7874D02*
G03Y0I0J3937D01*
G01X-738977D02*
X-769685D01*
G01X-755164Y-252763D02*
Y-235263D01*
G01X-746868D02*
X-755164Y-246055D01*
G01X-745558Y-252763D02*
X-751453Y-241097D01*
G01X-737883Y-252763D02*
Y-235263D01*
X-727839Y-252763D01*
Y-235263D01*
G01X-715361Y-252763D02*
X-717108Y-252471D01*
X-718636Y-251305D01*
X-719946Y-249555D01*
X-720820Y-247513D01*
X-721256Y-245180D01*
Y-242846D01*
X-720820Y-240513D01*
X-719946Y-238471D01*
X-718636Y-236722D01*
X-717108Y-235555D01*
X-715361Y-235263D01*
X-713615Y-235555D01*
X-712086Y-236722D01*
X-710776Y-238471D01*
X-709902Y-240513D01*
X-709466Y-242846D01*
Y-245180D01*
X-709902Y-247513D01*
X-710776Y-249555D01*
X-712086Y-251305D01*
X-713615Y-252471D01*
X-715361Y-252763D01*
G01X-702446D02*
X-693276Y-235263D01*
G01X-702446D02*
X-693276Y-252763D01*
G01X-658494D02*
X-667228D01*
Y-235263D01*
X-658494D01*
G01X-661988Y-243721D02*
X-667228D01*
G01X-649946Y-252763D02*
X-640776Y-235263D01*
G01X-649946D02*
X-640776Y-252763D01*
G01X-632228D02*
Y-235263D01*
X-626988D01*
X-625241Y-236138D01*
X-623931Y-238180D01*
X-623494Y-240513D01*
X-623931Y-242846D01*
X-625023Y-244596D01*
X-626988Y-245472D01*
X-632228D01*
G01X-615820Y-252763D02*
X-610361Y-235263D01*
X-604902Y-252763D01*
G01X-606868Y-246638D02*
X-613855D01*
G01X-597883Y-252763D02*
Y-235263D01*
X-587839Y-252763D01*
Y-235263D01*
G01X-580164Y-252763D02*
Y-235263D01*
X-575798D01*
X-574051Y-236138D01*
X-572741Y-237305D01*
X-571649Y-239054D01*
X-570776Y-241097D01*
X-570558Y-244013D01*
X-570776Y-246930D01*
X-571649Y-248972D01*
X-572741Y-250722D01*
X-574051Y-251888D01*
X-575798Y-252763D01*
X-580164D01*
G01X-553494D02*
X-562228D01*
Y-235263D01*
X-553494D01*
G01X-556988Y-243721D02*
X-562228D01*
G01X-544728Y-252763D02*
Y-235263D01*
X-539269D01*
X-537523Y-236138D01*
X-536431Y-237305D01*
X-535994Y-239638D01*
X-536431Y-241972D01*
X-537741Y-243430D01*
X-539269Y-244305D01*
X-544728D01*
G01X-539269D02*
X-535994Y-252763D01*
G01X-503615Y-243430D02*
X-502741Y-242555D01*
X-502086Y-241097D01*
X-501649Y-239054D01*
X-502086Y-237305D01*
X-502959Y-236138D01*
X-504488Y-235263D01*
X-510383D01*
Y-252763D01*
X-503178D01*
X-501649Y-251597D01*
X-500776Y-249846D01*
X-500339Y-247805D01*
X-500776Y-245763D01*
X-502086Y-244013D01*
X-503615Y-243430D01*
X-510383D01*
G01X-487861Y-252763D02*
X-489608Y-252471D01*
X-491136Y-251305D01*
X-492446Y-249555D01*
X-493320Y-247513D01*
X-493756Y-245180D01*
Y-242846D01*
X-493320Y-240513D01*
X-492446Y-238471D01*
X-491136Y-236722D01*
X-489608Y-235555D01*
X-487861Y-235263D01*
X-486115Y-235555D01*
X-484586Y-236722D01*
X-483276Y-238471D01*
X-482402Y-240513D01*
X-481966Y-242846D01*
Y-245180D01*
X-482402Y-247513D01*
X-483276Y-249555D01*
X-484586Y-251305D01*
X-486115Y-252471D01*
X-487861Y-252763D01*
G01X-475820D02*
X-470361Y-235263D01*
X-464902Y-252763D01*
G01X-466868Y-246638D02*
X-473855D01*
G01X-457228Y-252763D02*
Y-235263D01*
X-451769D01*
X-450023Y-236138D01*
X-448931Y-237305D01*
X-448494Y-239638D01*
X-448931Y-241972D01*
X-450241Y-243430D01*
X-451769Y-244305D01*
X-457228D01*
G01X-451769D02*
X-448494Y-252763D01*
G01X-440164D02*
Y-235263D01*
X-435798D01*
X-434051Y-236138D01*
X-432741Y-237305D01*
X-431649Y-239054D01*
X-430776Y-241097D01*
X-430558Y-244013D01*
X-430776Y-246930D01*
X-431649Y-248972D01*
X-432741Y-250722D01*
X-434051Y-251888D01*
X-435798Y-252763D01*
X-440164D01*
G01X-738977Y0D02*
G03Y-7874I0J-3937D01*
G01X-522835D02*
X-738977D01*
G01X-719292Y933071D02*
G03Y925197I0J-3937D01*
G01X-750000D02*
G03Y933071I0J3937D01*
G01X-719292D02*
X-512992D01*
G01X-750000Y925197D02*
X-719292D01*
G01X-633538Y-207763D02*
Y-190263D01*
X-627861Y-204846D01*
X-622184Y-190263D01*
Y-207763D01*
G01X-610361D02*
X-611671Y-207471D01*
X-612981Y-206305D01*
X-613855Y-204263D01*
X-614291Y-201930D01*
X-613855Y-199596D01*
X-612981Y-197555D01*
X-611671Y-196388D01*
X-610361Y-196097D01*
X-609051Y-196388D01*
X-607741Y-197555D01*
X-606868Y-199596D01*
X-606649Y-201930D01*
X-606868Y-204263D01*
X-607741Y-206305D01*
X-609051Y-207471D01*
X-610361Y-207763D01*
G01X-588931Y-190263D02*
Y-207763D01*
G01Y-205139D02*
X-589804Y-206597D01*
X-591115Y-207471D01*
X-592643Y-207763D01*
X-594389Y-207180D01*
X-595699Y-205722D01*
X-596573Y-203972D01*
X-596791Y-201930D01*
X-596573Y-199888D01*
X-595699Y-198138D01*
X-594389Y-196680D01*
X-592643Y-196097D01*
X-591115Y-196388D01*
X-590023Y-196972D01*
X-588931Y-198138D01*
G01X-578636Y-199888D02*
X-571649D01*
X-572304Y-197846D01*
X-573396Y-196680D01*
X-574924Y-196097D01*
X-576453Y-196388D01*
X-577763Y-197263D01*
X-578636Y-199305D01*
X-579073Y-201055D01*
Y-202805D01*
X-578636Y-204555D01*
X-577544Y-206305D01*
X-576234Y-207471D01*
X-574706Y-207763D01*
X-573178Y-207180D01*
X-571649Y-205430D01*
G01X-557861Y-207763D02*
Y-190263D01*
G01X-522835Y-7874D02*
G03Y0I0J3937D01*
G01X-492126D02*
G03Y-7874I0J-3937D01*
G01X-365355D02*
X-492126D01*
G01Y0D02*
X-522835D01*
G01X-482284Y933071D02*
G03Y925197I0J-3937D01*
G01X-512992D02*
G03Y933071I0J3937D01*
G01Y925197D02*
X-482284D01*
G01Y933071D02*
X-316142D01*
G01X-380161Y-252763D02*
Y-235263D01*
X-382781Y-238763D01*
G01Y-252763D02*
X-377541D01*
G01X-366809Y-238180D02*
X-365499Y-236430D01*
X-363971Y-235555D01*
X-362224Y-235263D01*
X-360041Y-235846D01*
X-358513Y-237305D01*
X-358076Y-239054D01*
X-358294Y-240805D01*
X-359168Y-242263D01*
X-363534Y-245180D01*
X-365499Y-247221D01*
X-366809Y-250139D01*
X-367246Y-252763D01*
X-358076D01*
G01X-345161Y-235263D02*
X-346908Y-235846D01*
X-348218Y-237305D01*
X-349091Y-239054D01*
X-349746Y-241388D01*
X-349964Y-244013D01*
X-349746Y-246638D01*
X-349091Y-248972D01*
X-348218Y-250722D01*
X-346908Y-252180D01*
X-345161Y-252763D01*
X-343415Y-252180D01*
X-342104Y-250722D01*
X-341231Y-248972D01*
X-340576Y-246638D01*
X-340358Y-244013D01*
X-340576Y-241388D01*
X-341231Y-239054D01*
X-342104Y-237305D01*
X-343415Y-235846D01*
X-345161Y-235263D01*
G01X-327661D02*
X-329408Y-235846D01*
X-330718Y-237305D01*
X-331591Y-239054D01*
X-332246Y-241388D01*
X-332464Y-244013D01*
X-332246Y-246638D01*
X-331591Y-248972D01*
X-330718Y-250722D01*
X-329408Y-252180D01*
X-327661Y-252763D01*
X-325915Y-252180D01*
X-324604Y-250722D01*
X-323731Y-248972D01*
X-323076Y-246638D01*
X-322858Y-244013D01*
X-323076Y-241388D01*
X-323731Y-239054D01*
X-324604Y-237305D01*
X-325915Y-235846D01*
X-327661Y-235263D01*
G01X-307541Y-252763D02*
Y-235263D01*
X-315620Y-247805D01*
X-304702D01*
G01X-393278Y-207763D02*
Y-190263D01*
X-388038D01*
X-386291Y-191138D01*
X-384981Y-193180D01*
X-384544Y-195513D01*
X-384981Y-197846D01*
X-386073Y-199596D01*
X-388038Y-200472D01*
X-393278D01*
G01X-366608Y-191722D02*
X-367918Y-190846D01*
X-369446Y-190263D01*
X-371193D01*
X-373158Y-191138D01*
X-374686Y-192596D01*
X-375778Y-194347D01*
X-376651Y-197263D01*
X-376870Y-199888D01*
X-376433Y-202513D01*
X-375778Y-204263D01*
X-374468Y-206013D01*
X-372939Y-207180D01*
X-371411Y-207763D01*
X-369883D01*
X-368354Y-207180D01*
X-367044Y-206305D01*
X-365952Y-205139D01*
G01X-352165Y-198430D02*
X-351291Y-197555D01*
X-350636Y-196097D01*
X-350199Y-194054D01*
X-350636Y-192305D01*
X-351509Y-191138D01*
X-353038Y-190263D01*
X-358933D01*
Y-207763D01*
X-351728D01*
X-350199Y-206597D01*
X-349326Y-204846D01*
X-348889Y-202805D01*
X-349326Y-200763D01*
X-350636Y-199013D01*
X-352165Y-198430D01*
X-358933D01*
G01X-342961Y-213596D02*
X-329861D01*
G01X-323933Y-207763D02*
Y-190263D01*
X-313889Y-207763D01*
Y-190263D01*
G01X-301411Y-207763D02*
X-303158Y-207471D01*
X-304686Y-206305D01*
X-305996Y-204555D01*
X-306870Y-202513D01*
X-307306Y-200180D01*
Y-197846D01*
X-306870Y-195513D01*
X-305996Y-193471D01*
X-304686Y-191722D01*
X-303158Y-190555D01*
X-301411Y-190263D01*
X-299665Y-190555D01*
X-298136Y-191722D01*
X-296826Y-193471D01*
X-295952Y-195513D01*
X-295516Y-197846D01*
Y-200180D01*
X-295952Y-202513D01*
X-296826Y-204555D01*
X-298136Y-206305D01*
X-299665Y-207471D01*
X-301411Y-207763D01*
G01X-365355Y-7874D02*
G03Y0I0J3937D01*
G01X-334646D02*
X-365355D01*
G01X-311024Y-7874D02*
G03X-307087Y-3937I0J3937D01*
G01X-334646Y0D02*
G03Y-7874I0J-3937D01*
G01X-311024D02*
X-334646D01*
G01X-318898Y0D02*
G03X-314961Y3937I0J3937D01*
G01X-274410Y31595D02*
G03X-270473Y35532I0J3937D01*
G01X-303150Y31595D02*
G03X-307087Y27658I0J-3937D01*
G01X-318898Y0D02*
G03X-314961Y3937I0J3937D01*
G01X-307087Y27658D02*
Y-3937D01*
G01X-314961Y133859D02*
Y3937D01*
G01Y133859D02*
Y3937D01*
G01X-274410Y31595D02*
X-303150D01*
G01X-311024Y137796D02*
G03X-314961Y133859I0J-3937D01*
G01X-311024Y137796D02*
G03X-314961Y133859I0J-3937D01*
G01X-240158Y137796D02*
X-311024D01*
G01X-240158D02*
X-311024D01*
G01X-285433Y933071D02*
G03Y925197I0J-3937D01*
G01X-316142D02*
G03Y933071I0J3937D01*
G01X-285433D02*
X-224410D01*
G01X-316142Y925197D02*
X-285433D01*
G01X-218861Y-252763D02*
Y-235263D01*
X-221481Y-238763D01*
G01Y-252763D02*
X-216241D01*
G01X-250570Y-190263D02*
X-245111Y-207763D01*
X-239652Y-190263D01*
G01X-223244Y-207763D02*
X-231978D01*
Y-190263D01*
X-223244D01*
G01X-226738Y-198721D02*
X-231978D01*
G01X-214478Y-207763D02*
Y-190263D01*
X-209019D01*
X-207273Y-191138D01*
X-206181Y-192305D01*
X-205744Y-194638D01*
X-206181Y-196972D01*
X-207491Y-198430D01*
X-209019Y-199305D01*
X-214478D01*
G01X-209019D02*
X-205744Y-207763D01*
G01X-192611Y-208346D02*
X-193048Y-208055D01*
Y-207471D01*
X-192611Y-207180D01*
X-192174Y-207471D01*
Y-208055D01*
X-192611Y-208346D01*
G01X-270473Y125985D02*
Y35532D01*
G01X-266536Y129922D02*
G03X-270473Y125985I0J-3937D01*
G01X-260630Y129922D02*
G03Y137796I0J3937D01*
G01X-244882D02*
G03Y129922I0J-3937D01*
G01X-240158D02*
G03X-228347Y141733I0J11811D01*
G01X-260630Y129922D02*
X-266536D01*
G01X-240158D02*
X-244882D01*
G01X-240158Y137796D02*
G03X-236221Y141733I0J3937D01*
G01X-240158Y137796D02*
G03X-236221Y141733I0J3937D01*
G01X-228347Y368701D02*
Y141733D01*
G01X-236221Y413386D02*
Y141733D01*
G01X-244882Y137796D02*
X-260630D01*
G01X-204725Y409449D02*
G03X-208662Y405512I0J-3937D01*
G01X-232284Y417323D02*
G03X-236221Y413386I0J-3937D01*
G01X-232284Y417323D02*
G03X-236221Y413386I0J-3937D01*
G01X-212599Y372638D02*
G03X-208662Y376575I0J3937D01*
G01X-224410Y372638D02*
G03X-228347Y368701I0J-3937D01*
G01X-181103Y409449D02*
X-204725D01*
G01X-212599Y372638D02*
X-224410D01*
G01X-208662Y405512D02*
Y376575D01*
G01X-232284Y417323D02*
X-181103D01*
G01X-232284D02*
X-181103D01*
G01X-236221Y716536D02*
G03X-232284Y712599I3937J0D01*
G01X-224410Y724410D02*
G03X-220473Y720473I3937J0D01*
G01X-236221Y716536D02*
G03X-232284Y712599I3937J0D01*
G01X-220473Y720473D02*
X-96418D01*
G01Y712599D02*
X-232284D01*
G01X-96418D02*
X-232284D01*
G01X-224410Y933071D02*
Y724410D01*
G01X-236221Y921260D02*
Y716536D01*
G01Y921260D02*
G03X-240158Y925197I-3937J0D01*
G01X-236221Y921260D02*
G03X-240158Y925197I-3937J0D01*
G01X-143740Y216536D02*
G03X-139803Y212599I3937J0D01*
G01X-143740Y262205D02*
G03X-151614I-3937J0D01*
G01X-143740Y216536D02*
G03X-139803Y212599I3937J0D01*
G01X-151614Y216536D02*
G03X-139803Y204725I11811J0D01*
G01X-143740Y262205D02*
Y292914D01*
G01Y338583D02*
Y216536D01*
G01Y338583D02*
Y216536D01*
G01X-151614D02*
Y262205D01*
G01X-139803Y212599D02*
X-3937D01*
G01X-139803D02*
X-3937D01*
G01X-15748Y204725D02*
X-139803D01*
G01Y342520D02*
G03X-143740Y338583I0J-3937D01*
G01X-139803Y342520D02*
G03X-143740Y338583I0J-3937D01*
G01X-139803Y350394D02*
G03X-151614Y338583I0J-11811D01*
G01Y292914D02*
G03X-143740I3937J0D01*
G01X-151614D02*
Y338583D01*
G01X-62992Y342520D02*
X-139803D01*
G01X-62992D02*
X-139803D01*
G01X-181103Y409449D02*
G03X-169292Y421260I0J11811D01*
G01X-139803Y350394D02*
X-70866D01*
G01X-177166Y467717D02*
G03X-169292I3937J0D01*
G01X-181103Y417323D02*
G03X-177166Y421260I0J3937D01*
G01X-169292Y437008D02*
G03X-177166I-3937J0D01*
G01X-181103Y417323D02*
G03X-177166Y421260I0J3937D01*
G01X-169292Y437008D02*
Y421260D01*
G01Y570866D02*
Y467717D01*
G01X-177166Y421260D02*
Y578740D01*
G01Y421260D02*
Y578740D01*
G01Y467717D02*
Y437008D01*
G01X-173229Y582677D02*
G03X-177166Y578740I0J-3937D01*
G01X-165355Y574803D02*
G03X-169292Y570866I0J-3937D01*
G01X-173229Y582677D02*
G03X-177166Y578740I0J-3937D01*
G01X-173229Y582677D02*
X-96418D01*
G01X-173229D02*
X-96418D01*
G01Y574803D02*
X-165355D01*
G01X-125778Y-190263D02*
Y-207763D01*
X-117044D01*
G01X-99981D02*
Y-196097D01*
G01Y-198138D02*
X-100854Y-196972D01*
X-102165Y-196388D01*
X-103693Y-196097D01*
X-105221Y-196680D01*
X-106531Y-197846D01*
X-107405Y-199596D01*
X-107841Y-201930D01*
X-107405Y-204263D01*
X-106531Y-206013D01*
X-105221Y-207180D01*
X-103693Y-207763D01*
X-102165Y-207471D01*
X-100854Y-206597D01*
X-99981Y-205430D01*
G01X-90996Y-213013D02*
X-89686Y-213596D01*
X-87939Y-213013D01*
X-86848Y-211847D01*
X-85974Y-210388D01*
X-84665Y-205722D01*
X-81826Y-196097D01*
G01X-88813D02*
X-84665Y-205722D01*
G01X-72186Y-199888D02*
X-65199D01*
X-65854Y-197846D01*
X-66946Y-196680D01*
X-68474Y-196097D01*
X-70003Y-196388D01*
X-71313Y-197263D01*
X-72186Y-199305D01*
X-72623Y-201055D01*
Y-202805D01*
X-72186Y-204555D01*
X-71094Y-206305D01*
X-69784Y-207471D01*
X-68256Y-207763D01*
X-66728Y-207180D01*
X-65199Y-205430D01*
G01X-54468Y-207763D02*
Y-196097D01*
G01Y-198430D02*
X-53376Y-197263D01*
X-52284Y-196388D01*
X-50756Y-196097D01*
X-49665Y-196388D01*
X-48354Y-197263D01*
G01X-37186Y-205722D02*
X-36094Y-206888D01*
X-34566Y-207763D01*
X-33256D01*
X-31946Y-207180D01*
X-31073Y-206305D01*
X-30636Y-205139D01*
X-30854Y-203388D01*
X-31728Y-202513D01*
X-35658Y-200763D01*
X-36531Y-198721D01*
X-36094Y-197263D01*
X-35221Y-196388D01*
X-33911Y-196097D01*
X-32601Y-196388D01*
X-31291Y-197263D01*
G01X-62992Y342520D02*
G03X-59055Y346457I0J3937D01*
G01X-62992Y342520D02*
G03X-59055Y346457I0J3937D01*
G01X-70866Y350394D02*
G03X-66929Y354331I0J3937D01*
G01D02*
Y457481D01*
G01Y488189D02*
G03X-59055I3937J0D01*
G01Y457481D02*
G03X-66929I-3937J0D01*
G01X-55118Y515748D02*
G03X-66929Y503937I0J-11811D01*
G01Y488189D02*
Y503937D01*
G01X-96418Y582677D02*
G03X-92481Y586615I0J3937D01*
G01X-96418Y582677D02*
G03X-92481Y586615I0J3937D01*
G01X-96418Y574803D02*
G03X-84607Y586615I0J11811D01*
G01Y632284D02*
Y586615D01*
G01X-92481D02*
Y708662D01*
G01Y586615D02*
Y708662D01*
G01Y662992D02*
G03X-84607I3937J0D01*
G01Y632284D02*
G03X-92481I-3937J0D01*
G01X-84607Y708662D02*
Y662992D01*
G01X-92481D02*
Y632284D01*
G01Y708662D02*
G03X-96418Y712599I-3937J0D01*
G01X-92481Y708662D02*
G03X-96418Y712599I-3937J0D01*
G01X-84607Y708662D02*
G03X-96418Y720473I-11811J0D01*
G01X-11811Y-3937D02*
G03X-7874Y-7874I3937J0D01*
G01X31496D02*
X-7874D01*
G01X0Y3937D02*
G03X3937Y0I3937J0D01*
G01X0Y3937D02*
G03X3937Y0I3937J0D01*
G01X0Y3937D02*
Y208662D01*
G01X-11811Y-3937D02*
Y200788D01*
G01X755905Y0D02*
X3937D01*
G01X755905D02*
X3937D01*
G01X-11811Y200788D02*
G03X-15748Y204725I-3937J0D01*
G01X0Y208662D02*
G03X-3937Y212599I-3937J0D01*
G01X0Y208662D02*
G03X-3937Y212599I-3937J0D01*
G01X-59055Y503937D02*
Y346457D01*
G01Y503937D02*
Y346457D01*
G01Y488189D02*
Y457481D01*
G01X-23622Y552559D02*
G03X-27559Y548622I0J-3937D01*
G01X-11811Y552559D02*
G03X-7874Y556496I0J3937D01*
G01X-3937Y507874D02*
G03X0Y511811I0J3937D01*
G01X-3937Y507874D02*
G03X0Y511811I0J3937D01*
G01X-55118Y507874D02*
G03X-59055Y503937I0J-3937D01*
G01X-31496Y515748D02*
G03X-27559Y519685I0J3937D01*
G01X-55118Y507874D02*
G03X-59055Y503937I0J-3937D01*
G01X-23622Y552559D02*
X-11811D01*
G01X0Y511811D02*
Y783465D01*
G01X-27559Y519685D02*
Y548622D01*
G01X-55118Y515748D02*
X-31496D01*
G01X-3937Y507874D02*
X-55118D01*
G01X-3937D02*
X-55118D01*
G01X-7874Y556496D02*
Y783465D01*
G01X3937Y787402D02*
G03X0Y783465I0J-3937D01*
G01X3937Y787402D02*
G03X0Y783465I0J-3937D01*
G01X3937Y795276D02*
G03X-7874Y783465I0J-11811D01*
G01X3937Y795276D02*
X8661D01*
G01X3937Y787402D02*
X74803D01*
G01X3937D02*
X74803D01*
G01X51772Y-235263D02*
Y-252763D01*
X60506D01*
G01X68836Y-235263D02*
Y-247805D01*
X69709Y-250430D01*
X71456Y-252180D01*
X73639Y-252763D01*
X75822Y-252180D01*
X77569Y-250430D01*
X78442Y-247805D01*
Y-235263D01*
G01X95942Y-236722D02*
X94632Y-235846D01*
X93104Y-235263D01*
X91357D01*
X89392Y-236138D01*
X87864Y-237596D01*
X86772Y-239347D01*
X85899Y-242263D01*
X85680Y-244888D01*
X86117Y-247513D01*
X86772Y-249263D01*
X88082Y-251013D01*
X89611Y-252180D01*
X91139Y-252763D01*
X92667D01*
X94196Y-252180D01*
X95506Y-251305D01*
X96598Y-250139D01*
G01X103836Y-252763D02*
Y-235263D01*
G01X112132D02*
X103836Y-246055D01*
G01X113442Y-252763D02*
X107547Y-241097D01*
G01X126139Y-252763D02*
Y-244888D01*
X121772Y-235263D01*
G01X130506D02*
X126139Y-244888D01*
G01X25086Y-207763D02*
Y-190263D01*
X29452D01*
X31199Y-191138D01*
X32509Y-192305D01*
X33601Y-194054D01*
X34474Y-196097D01*
X34692Y-199013D01*
X34474Y-201930D01*
X33601Y-203972D01*
X32509Y-205722D01*
X31199Y-206888D01*
X29452Y-207763D01*
X25086D01*
G01X44114Y-199888D02*
X51101D01*
X50446Y-197846D01*
X49354Y-196680D01*
X47826Y-196097D01*
X46297Y-196388D01*
X44987Y-197263D01*
X44114Y-199305D01*
X43677Y-201055D01*
Y-202805D01*
X44114Y-204555D01*
X45206Y-206305D01*
X46516Y-207471D01*
X48044Y-207763D01*
X49572Y-207180D01*
X51101Y-205430D01*
G01X61614Y-205722D02*
X62706Y-206888D01*
X64234Y-207763D01*
X65544D01*
X66854Y-207180D01*
X67727Y-206305D01*
X68164Y-205139D01*
X67946Y-203388D01*
X67072Y-202513D01*
X63142Y-200763D01*
X62269Y-198721D01*
X62706Y-197263D01*
X63579Y-196388D01*
X64889Y-196097D01*
X66199Y-196388D01*
X67509Y-197263D01*
G01X82389Y-196097D02*
Y-207763D01*
G01Y-191430D02*
X81952Y-191138D01*
Y-190555D01*
X82389Y-190263D01*
X82826Y-190555D01*
Y-191138D01*
X82389Y-191430D01*
G01X96832Y-212138D02*
X98361Y-213305D01*
X100107Y-213596D01*
X101635Y-213305D01*
X102946Y-211847D01*
X103819Y-209805D01*
Y-196097D01*
G01Y-198430D02*
X102946Y-197263D01*
X101635Y-196388D01*
X100107Y-196097D01*
X98361Y-196680D01*
X97269Y-197846D01*
X96395Y-199888D01*
X95959Y-201930D01*
X96177Y-203680D01*
X97051Y-205722D01*
X98361Y-207180D01*
X100107Y-207763D01*
X101417Y-207471D01*
X102946Y-206305D01*
X103819Y-205139D01*
G01X113677Y-207763D02*
Y-196097D01*
G01Y-199013D02*
X114551Y-197555D01*
X115861Y-196388D01*
X117607Y-196097D01*
X119135Y-196388D01*
X120446Y-197555D01*
X121101Y-199596D01*
Y-207763D01*
G01X131614Y-199888D02*
X138601D01*
X137946Y-197846D01*
X136854Y-196680D01*
X135326Y-196097D01*
X133797Y-196388D01*
X132487Y-197263D01*
X131614Y-199305D01*
X131177Y-201055D01*
Y-202805D01*
X131614Y-204555D01*
X132706Y-206305D01*
X134016Y-207471D01*
X135544Y-207763D01*
X137072Y-207180D01*
X138601Y-205430D01*
G01X149332Y-207763D02*
Y-196097D01*
G01Y-198430D02*
X150424Y-197263D01*
X151516Y-196388D01*
X153044Y-196097D01*
X154135Y-196388D01*
X155446Y-197263D01*
G01X62204Y0D02*
G03Y-7874I0J-3937D01*
G01X31496D02*
G03Y0I0J3937D01*
G01X267716Y-7874D02*
X62204D01*
G01Y0D02*
X31496D01*
G01X74803Y787402D02*
G03X78740Y791339I0J3937D01*
G01X30315Y795276D02*
G03X34252Y799213I0J3937D01*
G01X24409Y795276D02*
G03Y787402I0J-3937D01*
G01X8661D02*
G03Y795276I0J3937D01*
G01X74803Y787402D02*
G03X78740Y791339I0J3937D01*
G01X24409Y795276D02*
X30315D01*
G01X24409Y787402D02*
X8661D01*
G01X34252Y799213D02*
Y889666D01*
G01X38189Y893603D02*
G03X34252Y889666I0J-3937D01*
G01X66929Y893603D02*
G03X70866Y897540I0J3937D01*
G01X38189Y893603D02*
X66929D01*
G01X70866Y897540D02*
Y929134D01*
G01X74803Y933071D02*
G03X70866Y929134I0J-3937D01*
G01X74803Y933071D02*
X88582D01*
G01X78740Y791339D02*
Y921260D01*
G01Y791339D02*
Y921260D01*
G01X119291Y933071D02*
G03Y925197I0J-3937D01*
G01X82677D02*
G03X78740Y921260I0J-3937D01*
G01X88582Y925197D02*
G03Y933071I0J3937D01*
G01X82677Y925197D02*
G03X78740Y921260I0J-3937D01*
G01X119291Y933071D02*
X305118D01*
G01X82677Y925197D02*
X755905D01*
G01X82677D02*
X755905D01*
G01X119291D02*
X88582D01*
G01X196089Y-252763D02*
Y-235263D01*
X193469Y-238763D01*
G01Y-252763D02*
X198709D01*
G01X213589Y-235263D02*
X211842Y-235846D01*
X210532Y-237305D01*
X209659Y-239054D01*
X209004Y-241388D01*
X208786Y-244013D01*
X209004Y-246638D01*
X209659Y-248972D01*
X210532Y-250722D01*
X211842Y-252180D01*
X213589Y-252763D01*
X215335Y-252180D01*
X216646Y-250722D01*
X217519Y-248972D01*
X218174Y-246638D01*
X218392Y-244013D01*
X218174Y-241388D01*
X217519Y-239054D01*
X216646Y-237305D01*
X215335Y-235846D01*
X213589Y-235263D01*
G01X227159Y-253346D02*
X235019Y-235263D01*
G01X248589Y-252763D02*
Y-235263D01*
X245969Y-238763D01*
G01Y-252763D02*
X251209D01*
G01X261941Y-245472D02*
X263469Y-243430D01*
X264779Y-242263D01*
X266526Y-241680D01*
X268054Y-242263D01*
X269146Y-243430D01*
X270019Y-245180D01*
X270237Y-247221D01*
X270019Y-248972D01*
X269146Y-250722D01*
X267835Y-252180D01*
X266307Y-252763D01*
X264561Y-252180D01*
X263032Y-250430D01*
X262159Y-247805D01*
X261941Y-244888D01*
X262377Y-241097D01*
X263032Y-239054D01*
X264124Y-237013D01*
X265652Y-235555D01*
X267181Y-235263D01*
X268709Y-235846D01*
X269801Y-237305D01*
G01X279659Y-253346D02*
X287519Y-235263D01*
G01X296941Y-238180D02*
X298251Y-236430D01*
X299779Y-235555D01*
X301526Y-235263D01*
X303709Y-235846D01*
X305237Y-237305D01*
X305674Y-239054D01*
X305456Y-240805D01*
X304582Y-242263D01*
X300216Y-245180D01*
X298251Y-247221D01*
X296941Y-250139D01*
X296504Y-252763D01*
X305674D01*
G01X318589Y-235263D02*
X316842Y-235846D01*
X315532Y-237305D01*
X314659Y-239054D01*
X314004Y-241388D01*
X313786Y-244013D01*
X314004Y-246638D01*
X314659Y-248972D01*
X315532Y-250722D01*
X316842Y-252180D01*
X318589Y-252763D01*
X320335Y-252180D01*
X321646Y-250722D01*
X322519Y-248972D01*
X323174Y-246638D01*
X323392Y-244013D01*
X323174Y-241388D01*
X322519Y-239054D01*
X321646Y-237305D01*
X320335Y-235846D01*
X318589Y-235263D01*
G01X336089Y-252763D02*
Y-235263D01*
X333469Y-238763D01*
G01Y-252763D02*
X338709D01*
G01X349441Y-238180D02*
X350751Y-236430D01*
X352279Y-235555D01*
X354026Y-235263D01*
X356209Y-235846D01*
X357737Y-237305D01*
X358174Y-239054D01*
X357956Y-240805D01*
X357082Y-242263D01*
X352716Y-245180D01*
X350751Y-247221D01*
X349441Y-250139D01*
X349004Y-252763D01*
X358174D01*
G01X243786Y-207763D02*
Y-190263D01*
X248152D01*
X249899Y-191138D01*
X251209Y-192305D01*
X252301Y-194054D01*
X253174Y-196097D01*
X253392Y-199013D01*
X253174Y-201930D01*
X252301Y-203972D01*
X251209Y-205722D01*
X249899Y-206888D01*
X248152Y-207763D01*
X243786D01*
G01X270019D02*
Y-196097D01*
G01Y-198138D02*
X269146Y-196972D01*
X267835Y-196388D01*
X266307Y-196097D01*
X264779Y-196680D01*
X263469Y-197846D01*
X262595Y-199596D01*
X262159Y-201930D01*
X262595Y-204263D01*
X263469Y-206013D01*
X264779Y-207180D01*
X266307Y-207763D01*
X267835Y-207471D01*
X269146Y-206597D01*
X270019Y-205430D01*
G01X283589Y-190263D02*
Y-207763D01*
G01X280532Y-196097D02*
X286646D01*
G01X297814Y-199888D02*
X304801D01*
X304146Y-197846D01*
X303054Y-196680D01*
X301526Y-196097D01*
X299997Y-196388D01*
X298687Y-197263D01*
X297814Y-199305D01*
X297377Y-201055D01*
Y-202805D01*
X297814Y-204555D01*
X298906Y-206305D01*
X300216Y-207471D01*
X301744Y-207763D01*
X303272Y-207180D01*
X304801Y-205430D01*
G01X267716Y-7874D02*
G03Y0I0J3937D01*
G01X298425D02*
X267716D01*
G01X298425D02*
G03Y-7874I0J-3937D01*
G01X483071D02*
X298425D01*
G01X335827Y933071D02*
G03Y925197I0J-3937D01*
G01X305118D02*
G03Y933071I0J3937D01*
G01X335827D02*
X522441D01*
G01X335827Y925197D02*
X305118D01*
G01X483071Y-7874D02*
G03Y0I0J3937D01*
G01X513779D02*
X483071D01*
G01X513779D02*
G03Y-7874I0J-3937D01*
G01X719291D02*
X513779D01*
G01X553149Y933071D02*
G03Y925197I0J-3937D01*
G01X522441D02*
G03Y933071I0J3937D01*
G01X553149D02*
X719291D01*
G01X553149Y925197D02*
X522441D01*
G01X763779Y-7874D02*
G03X767716Y-3937I0J3937D01*
G01X719291Y-7874D02*
G03Y0I0J3937D01*
G01X750000D02*
G03Y-7874I0J-3937D01*
G01X763779D02*
X750000D01*
G01X755905Y0D02*
G03X759842Y3937I0J3937D01*
G01X755905Y0D02*
G03X759842Y3937I0J3937D01*
G01X767716Y185827D02*
Y-3937D01*
G01X759842Y3937D02*
Y324213D01*
G01X750000Y0D02*
X719291D01*
G01X767716Y185827D02*
G03X759842I-3937J0D01*
G01Y216536D02*
Y185827D01*
G01Y216536D02*
G03X767716I3937J0D01*
G01Y316339D02*
Y216536D01*
G01X771653Y320276D02*
G03X767716Y316339I0J-3937D01*
G01X763779Y328150D02*
G03X759842Y324213I0J-3937D01*
G01X793307Y328150D02*
X763779D01*
G01X791338Y320276D02*
X771653D01*
G01X765945Y379725D02*
G03Y372244I0J-3741D01*
G01X793307Y379725D02*
X765945D01*
G01X793307Y372244D02*
X765945D01*
G01X759842Y663977D02*
G03X763779Y660040I3937J0D01*
G01X759842Y663977D02*
Y733662D01*
G01X793307Y660040D02*
X763779D01*
G01Y737599D02*
G03X759842Y733662I0J-3937D01*
G01X793307Y737599D02*
X763779D01*
G01X765945Y789174D02*
G03Y781693I0J-3740D01*
G01X767716Y829331D02*
G03X771653Y825394I3937J0D01*
G01X759842Y821457D02*
G03X763779Y817520I3937J0D01*
G01X767716Y855118D02*
Y829331D01*
G01X759842Y921260D02*
Y821457D01*
G01X771653Y825394D02*
X791338D01*
G01X793307Y817520D02*
X763779D01*
G01X793307Y789174D02*
X765945D01*
G01X793307Y781693D02*
X765945D01*
G01X767716Y855118D02*
G03X759842I-3937J0D01*
G01Y885827D02*
G03X767716I3937J0D01*
G01Y929134D02*
Y885827D01*
G01X759842D02*
Y855118D01*
G01Y921260D02*
G03X755905Y925197I-3937J0D01*
G01X767716Y929134D02*
G03X763779Y933071I-3937J0D01*
G01X750000D02*
G03Y925197I0J-3937D01*
G01X719291D02*
G03Y933071I0J3937D01*
G01X759842Y921260D02*
G03X755905Y925197I-3937J0D01*
G01X750000Y933071D02*
X763779D01*
G01X750000Y925197D02*
X719291D01*
G01X791338Y-35433D02*
G03X795275Y-31496I0J3937D01*
G01D02*
Y316339D01*
G01D02*
G03X791338Y320276I-3937J0D01*
G01X795275Y370276D02*
Y330118D01*
G01D02*
X793307Y328150D01*
G01X795275Y658071D02*
Y381693D01*
G01D02*
X793307Y379725D01*
G01X795275Y370276D02*
X793307Y372244D01*
G01X795275Y658071D02*
X793307Y660040D01*
G01X795275Y779725D02*
Y739567D01*
G01D02*
X793307Y737599D01*
G01X791338Y825394D02*
G03X795275Y829331I0J3937D01*
G01D02*
Y956693D01*
G01Y815552D02*
Y791142D01*
G01Y815552D02*
X793307Y817520D01*
G01X795275Y779725D02*
X793307Y781693D01*
G01X795275Y791142D02*
X793307Y789174D01*
G01X795275Y956693D02*
G03X791338Y960630I-3937J0D01*
M02*
